(kicad_pcb
	(version 20260206)
	(generator "pcbnew")
	(generator_version "10.0")
	(general
		(thickness 1.6)
		(legacy_teardrops no)
	)
	(paper "A4")
	(title_block
		(title "03242023_DA0F0TMBIJ0_F0T_Motherboard_J_brd_V01_OCP.brd")
		(comment 1 "Grand Teton / footprints 3389-3393 of 6105")
	)
	(layers
		(0 "F.Cu" signal "TOP")
		(4 "In1.Cu" signal "GND")
		(6 "In2.Cu" signal "IN1")
		(8 "In3.Cu" signal "GND1")
		(10 "In4.Cu" signal "IN2")
		(12 "In5.Cu" signal "GND2")
		(14 "In6.Cu" signal "IN3")
		(16 "In7.Cu" signal "GND3")
		(18 "In8.Cu" signal "VCC")
		(20 "In9.Cu" signal "VCC1")
		(22 "In10.Cu" signal "GND4")
		(24 "In11.Cu" signal "IN4")
		(26 "In12.Cu" signal "GND5")
		(28 "In13.Cu" signal "IN5")
		(30 "In14.Cu" signal "GND6")
		(32 "In15.Cu" signal "IN6")
		(34 "In16.Cu" signal "GND7")
		(2 "B.Cu" signal "BOTTOM")
		(9 "F.Adhes" user "F.Adhesive")
		(11 "B.Adhes" user "B.Adhesive")
		(13 "F.Paste" user "Package Geometry/Pastemask Top")
		(15 "B.Paste" user "Package Geometry/Pastemask Bottom")
		(5 "F.SilkS" user "Ref Des/Silkscreen Top")
		(7 "B.SilkS" user "Ref Des/Silkscreen Bottom")
		(1 "F.Mask" user "Board Geometry/Soldermask Top")
		(3 "B.Mask" user "Board Geometry/Soldermask Bottom")
		(17 "Dwgs.User" user "User.Drawings")
		(19 "Cmts.User" user "User.Comments")
		(21 "Eco1.User" user "User.Eco1")
		(23 "Eco2.User" user "User.Eco2")
		(25 "Edge.Cuts" user "Board Geometry/Outline")
		(27 "Margin" user)
		(31 "F.CrtYd" user "Package Geometry/Place Bound Top")
		(29 "B.CrtYd" user "Package Geometry/Place Bound Bottom")
		(35 "F.Fab" user "Ref Des/Assembly Top")
		(33 "B.Fab" user "Ref Des/Assembly Bottom")
	)
	(footprint ""
		(layer "F.Cu")
		(at 127.288544 -77.571092 180)
		(property "Reference" "U96"
			(at -0.257556 3.718306 0)
			(unlocked yes)
			(layer "F.SilkS")
			(effects
				(font
					(size 0.7874 0.5842)
					(thickness 0.1524)
				)
				(justify left)
			)
		)
		(property "Value" ""
			(at 0 0 180)
			(layer "F.Fab")
			(effects
				(font
					(size 1.27 1.27)
				)
			)
		)
		(duplicate_pad_numbers_are_jumpers no)
		(fp_line
			(start 0.824992 1.050036)
			(end 0.254 1.050036)
			(stroke
				(width 0.1524)
				(type default)
			)
			(layer "F.SilkS")
		)
		(fp_line
			(start 0.824992 1.00584)
			(end 0.824992 1.050036)
			(stroke
				(width 0.1524)
				(type default)
			)
			(layer "F.SilkS")
		)
		(fp_line
			(start 0.824992 -1.050036)
			(end 0.824992 -1.00584)
			(stroke
				(width 0.1524)
				(type default)
			)
			(layer "F.SilkS")
		)
		(fp_line
			(start 0.254 -1.050036)
			(end 0.824992 -1.050036)
			(stroke
				(width 0.1524)
				(type default)
			)
			(layer "F.SilkS")
		)
		(fp_line
			(start -0.254 1.050036)
			(end -0.824992 1.050036)
			(stroke
				(width 0.1524)
				(type default)
			)
			(layer "F.SilkS")
		)
		(fp_line
			(start -0.824992 1.050036)
			(end -0.824992 1.00584)
			(stroke
				(width 0.1524)
				(type default)
			)
			(layer "F.SilkS")
		)
		(fp_line
			(start -0.824992 -1.01854)
			(end -0.824992 -1.050036)
			(stroke
				(width 0.1524)
				(type default)
			)
			(layer "F.SilkS")
		)
		(fp_line
			(start -0.824992 -1.050036)
			(end -0.254 -1.050036)
			(stroke
				(width 0.1524)
				(type default)
			)
			(layer "F.SilkS")
		)
		(fp_poly
			(pts
				(xy -1.969008 -0.411734) (xy -1.969008 -1.11379) (xy -1.266952 -0.762762)
			)
			(stroke
				(width 0)
				(type default)
			)
			(fill yes)
			(layer "F.SilkS")
		)
		(fp_line
			(start 0.824992 1.050036)
			(end -0.824992 1.050036)
			(stroke
				(width 0.1)
				(type default)
			)
			(layer "F.Fab")
		)
		(fp_line
			(start 0.824992 -1.050036)
			(end 0.824992 1.050036)
			(stroke
				(width 0.1)
				(type default)
			)
			(layer "F.Fab")
		)
		(fp_line
			(start -0.824992 1.050036)
			(end -0.824992 -1.050036)
			(stroke
				(width 0.1)
				(type default)
			)
			(layer "F.Fab")
		)
		(fp_line
			(start -0.824992 -1.050036)
			(end 0.824992 -1.050036)
			(stroke
				(width 0.1)
				(type default)
			)
			(layer "F.Fab")
		)
		(fp_poly
			(pts
				(xy -1.325372 -0.750062) (xy -2.027428 -0.399034) (xy -2.027428 -1.10109)
			)
			(stroke
				(width 0)
				(type default)
			)
			(fill yes)
			(layer "F.Fab")
		)
		(pad "1" smd rect
			(at -0.741172 -0.750062 270)
			(size 0.2794 0.8128)
			(layers "F.Cu" "F.Mask" "F.Paste")
			(net "JTAG_BMC_PLD_TDI")
		)
		(pad "2" smd rect
			(at -0.741172 -0.249936 270)
			(size 0.254 0.8128)
			(layers "F.Cu" "F.Mask" "F.Paste")
			(net "JTAG_BMC_DBP_TDI")
		)
		(pad "3" smd rect
			(at -0.741172 0.249936 270)
			(size 0.254 0.8128)
			(layers "F.Cu" "F.Mask" "F.Paste")
			(net "JTAG_BMC_PLD_TDO")
		)
		(pad "4" smd rect
			(at -0.741172 0.750062 270)
			(size 0.254 0.8128)
			(layers "F.Cu" "F.Mask" "F.Paste")
			(net "JTAG_BMC_DBP_TDO")
		)
		(pad "5" smd rect
			(at 0 0.94996 180)
			(size 0.254 0.8128)
			(layers "F.Cu" "F.Mask" "F.Paste")
			(net "GND")
		)
		(pad "6" smd rect
			(at 0.741172 0.750062 270)
			(size 0.254 0.8128)
			(layers "F.Cu" "F.Mask" "F.Paste")
			(net "JTAG_BMC_SW_TDO")
		)
		(pad "7" smd rect
			(at 0.741172 0.249936 270)
			(size 0.254 0.8128)
			(layers "F.Cu" "F.Mask" "F.Paste")
			(net "FM_JTAG_BMC_MUX_SEL")
		)
		(pad "8" smd rect
			(at 0.741172 -0.249936 270)
			(size 0.254 0.8128)
			(layers "F.Cu" "F.Mask" "F.Paste")
			(net "FM_JTAG_BMC_MUX_SEL")
		)
		(pad "9" smd rect
			(at 0.741172 -0.750062 270)
			(size 0.254 0.8128)
			(layers "F.Cu" "F.Mask" "F.Paste")
			(net "JTAG_BMC_SW_TDI")
		)
		(pad "10" smd rect
			(at 0 -0.94996 180)
			(size 0.254 0.8128)
			(layers "F.Cu" "F.Mask" "F.Paste")
			(net "P3V3_AUX")
		)
		(zone
			(layer "F.Cu")
			(hatch none 0.5)
			(connect_pads
				(clearance 0)
			)
			(min_thickness 0.25)
			(keepout
				(tracks not_allowed)
				(vias allowed)
				(pads allowed)
				(copperpour not_allowed)
				(footprints allowed)
			)
			(placement
				(enabled no)
				(sheetname "")
			)
			(fill
				(thermal_gap 0.5)
				(thermal_bridge_width 0.5)
				(island_removal_mode 0)
			)
			(polygon
				(pts
					(xy 128.114044 -76.631292) (xy 128.114044 -76.516992) (xy 127.567944 -76.516992) (xy 127.567944 -76.631292)
				)
			)
		)
	)
	(footprint ""
		(layer "F.Cu")
		(at 127.04064 -156.365448 180)
		(property "Reference" "R1493"
			(at 0 0 180)
			(layer "F.SilkS")
			(hide yes)
			(effects
				(font
					(size 1.27 1.27)
				)
			)
		)
		(property "Value" ""
			(at 0 0 180)
			(layer "F.Fab")
			(effects
				(font
					(size 1.27 1.27)
				)
			)
		)
		(duplicate_pad_numbers_are_jumpers no)
		(fp_line
			(start 0.7874 0.4064)
			(end -0.7874 0.4064)
			(stroke
				(width 0.1524)
				(type default)
			)
			(layer "F.SilkS")
		)
		(fp_line
			(start 0.7874 -0.4064)
			(end 0.7874 0.4064)
			(stroke
				(width 0.1524)
				(type default)
			)
			(layer "F.SilkS")
		)
		(fp_line
			(start -0.7874 0.4064)
			(end -0.7874 -0.4064)
			(stroke
				(width 0.1524)
				(type default)
			)
			(layer "F.SilkS")
		)
		(fp_line
			(start -0.7874 -0.4064)
			(end 0.7874 -0.4064)
			(stroke
				(width 0.1524)
				(type default)
			)
			(layer "F.SilkS")
		)
		(fp_line
			(start 0.67945 0.3048)
			(end 0.120396 0.3048)
			(stroke
				(width 0.1)
				(type default)
			)
			(layer "F.Fab")
		)
		(fp_line
			(start 0.67945 -0.3048)
			(end 0.67945 0.3048)
			(stroke
				(width 0.1)
				(type default)
			)
			(layer "F.Fab")
		)
		(fp_line
			(start 0.12065 -0.2794)
			(end 0.12065 -0.3048)
			(stroke
				(width 0.1)
				(type default)
			)
			(layer "F.Fab")
		)
		(fp_line
			(start 0.12065 -0.3048)
			(end 0.67945 -0.3048)
			(stroke
				(width 0.1)
				(type default)
			)
			(layer "F.Fab")
		)
		(fp_line
			(start 0.120396 0.3048)
			(end 0.120396 0.2794)
			(stroke
				(width 0.1)
				(type default)
			)
			(layer "F.Fab")
		)
		(fp_line
			(start 0.120396 0.2794)
			(end -0.12065 0.2794)
			(stroke
				(width 0.1)
				(type default)
			)
			(layer "F.Fab")
		)
		(fp_line
			(start -0.12065 0.3048)
			(end -0.67945 0.3048)
			(stroke
				(width 0.1)
				(type default)
			)
			(layer "F.Fab")
		)
		(fp_line
			(start -0.12065 0.2794)
			(end -0.12065 0.3048)
			(stroke
				(width 0.1)
				(type default)
			)
			(layer "F.Fab")
		)
		(fp_line
			(start -0.12065 -0.2794)
			(end 0.12065 -0.2794)
			(stroke
				(width 0.1)
				(type default)
			)
			(layer "F.Fab")
		)
		(fp_line
			(start -0.12065 -0.305054)
			(end -0.12065 -0.2794)
			(stroke
				(width 0.1)
				(type default)
			)
			(layer "F.Fab")
		)
		(fp_line
			(start -0.67945 0.3048)
			(end -0.67945 -0.305054)
			(stroke
				(width 0.1)
				(type default)
			)
			(layer "F.Fab")
		)
		(fp_line
			(start -0.67945 -0.305054)
			(end -0.12065 -0.305054)
			(stroke
				(width 0.1)
				(type default)
			)
			(layer "F.Fab")
		)
		(pad "1" smd circle
			(at -0.40005 0 180)
			(size 0 0)
			(layers "F.Cu" "F.Mask" "F.Paste")
			(net "P3V3_AUX")
		)
		(pad "2" smd circle
			(at 0.40005 0 180)
			(size 0 0)
			(layers "F.Cu" "F.Mask" "F.Paste")
			(net "PU_FORCE_PWRON")
		)
	)
	(footprint ""
		(layer "F.Cu")
		(at 117.526816 -247.715278 90)
		(property "Reference" "C273"
			(at 0 0 90)
			(layer "F.SilkS")
			(hide yes)
			(effects
				(font
					(size 1.27 1.27)
				)
			)
		)
		(property "Value" ""
			(at 0 0 90)
			(layer "F.Fab")
			(effects
				(font
					(size 1.27 1.27)
				)
			)
		)
		(duplicate_pad_numbers_are_jumpers no)
		(fp_line
			(start 0.7874 -0.4064)
			(end 0.7874 0.4064)
			(stroke
				(width 0.1524)
				(type default)
			)
			(layer "F.SilkS")
		)
		(fp_line
			(start -0.7874 -0.4064)
			(end 0.7874 -0.4064)
			(stroke
				(width 0.1524)
				(type default)
			)
			(layer "F.SilkS")
		)
		(fp_line
			(start 0.7874 0.4064)
			(end -0.7874 0.4064)
			(stroke
				(width 0.1524)
				(type default)
			)
			(layer "F.SilkS")
		)
		(fp_line
			(start -0.7874 0.4064)
			(end -0.7874 -0.4064)
			(stroke
				(width 0.1524)
				(type default)
			)
			(layer "F.SilkS")
		)
		(fp_line
			(start -0.12065 -0.305054)
			(end -0.12065 -0.2794)
			(stroke
				(width 0.1)
				(type default)
			)
			(layer "F.Fab")
		)
		(fp_line
			(start -0.67945 -0.305054)
			(end -0.12065 -0.305054)
			(stroke
				(width 0.1)
				(type default)
			)
			(layer "F.Fab")
		)
		(fp_line
			(start 0.67945 -0.3048)
			(end 0.67945 0.3048)
			(stroke
				(width 0.1)
				(type default)
			)
			(layer "F.Fab")
		)
		(fp_line
			(start 0.12065 -0.3048)
			(end 0.67945 -0.3048)
			(stroke
				(width 0.1)
				(type default)
			)
			(layer "F.Fab")
		)
		(fp_line
			(start 0.12065 -0.2794)
			(end 0.12065 -0.3048)
			(stroke
				(width 0.1)
				(type default)
			)
			(layer "F.Fab")
		)
		(fp_line
			(start -0.12065 -0.2794)
			(end 0.12065 -0.2794)
			(stroke
				(width 0.1)
				(type default)
			)
			(layer "F.Fab")
		)
		(fp_line
			(start 0.120396 0.2794)
			(end -0.12065 0.2794)
			(stroke
				(width 0.1)
				(type default)
			)
			(layer "F.Fab")
		)
		(fp_line
			(start -0.12065 0.2794)
			(end -0.12065 0.3048)
			(stroke
				(width 0.1)
				(type default)
			)
			(layer "F.Fab")
		)
		(fp_line
			(start 0.67945 0.3048)
			(end 0.120396 0.3048)
			(stroke
				(width 0.1)
				(type default)
			)
			(layer "F.Fab")
		)
		(fp_line
			(start 0.120396 0.3048)
			(end 0.120396 0.2794)
			(stroke
				(width 0.1)
				(type default)
			)
			(layer "F.Fab")
		)
		(fp_line
			(start -0.12065 0.3048)
			(end -0.67945 0.3048)
			(stroke
				(width 0.1)
				(type default)
			)
			(layer "F.Fab")
		)
		(fp_line
			(start -0.67945 0.3048)
			(end -0.67945 -0.305054)
			(stroke
				(width 0.1)
				(type default)
			)
			(layer "F.Fab")
		)
		(pad "1" smd circle
			(at -0.40005 0 90)
			(size 0 0)
			(layers "F.Cu" "F.Mask" "F.Paste")
			(net "PVCCIN_CPU1")
		)
		(pad "2" smd circle
			(at 0.40005 0 90)
			(size 0 0)
			(layers "F.Cu" "F.Mask" "F.Paste")
			(net "GND")
		)
	)
	(footprint ""
		(layer "F.Cu")
		(at 85.626194 -102.509574 180)
		(property "Reference" "Q100"
			(at 3.226308 0.425196 0)
			(unlocked yes)
			(layer "F.SilkS")
			(effects
				(font
					(size 0.7874 0.5842)
					(thickness 0.1524)
				)
			)
		)
		(property "Value" ""
			(at 0 0 180)
			(layer "F.Fab")
			(effects
				(font
					(size 1.27 1.27)
				)
			)
		)
		(duplicate_pad_numbers_are_jumpers no)
		(fp_line
			(start 1.376172 1.199896)
			(end -1.376172 1.199896)
			(stroke
				(width 0.1524)
				(type default)
			)
			(layer "F.SilkS")
		)
		(fp_line
			(start 1.376172 -1.199896)
			(end 1.376172 1.199896)
			(stroke
				(width 0.1524)
				(type default)
			)
			(layer "F.SilkS")
		)
		(fp_line
			(start 0.508 -1.199896)
			(end 1.376172 -1.199896)
			(stroke
				(width 0.1524)
				(type default)
			)
			(layer "F.SilkS")
		)
		(fp_line
			(start 0 -0.762)
			(end 0.508 -1.199896)
			(stroke
				(width 0.1524)
				(type default)
			)
			(layer "F.SilkS")
		)
		(fp_line
			(start -0.508 -1.199896)
			(end 0 -0.762)
			(stroke
				(width 0.1524)
				(type default)
			)
			(layer "F.SilkS")
		)
		(fp_line
			(start -1.376172 1.199896)
			(end -1.376172 -1.199896)
			(stroke
				(width 0.1524)
				(type default)
			)
			(layer "F.SilkS")
		)
		(fp_line
			(start -1.376172 -1.199896)
			(end -0.508 -1.199896)
			(stroke
				(width 0.1524)
				(type default)
			)
			(layer "F.SilkS")
		)
		(fp_poly
			(pts
				(xy -2.04724 -0.7747) (xy -2.80924 -0.3937) (xy -2.80924 -1.1557)
			)
			(stroke
				(width 0)
				(type default)
			)
			(fill yes)
			(layer "F.SilkS")
		)
		(fp_line
			(start 0.674878 1.100074)
			(end -0.674878 1.100074)
			(stroke
				(width 0.1)
				(type default)
			)
			(layer "F.Fab")
		)
		(fp_line
			(start 0.674878 -1.100074)
			(end 0.674878 1.100074)
			(stroke
				(width 0.1)
				(type default)
			)
			(layer "F.Fab")
		)
		(fp_line
			(start -0.674878 1.100074)
			(end -0.674878 -1.100074)
			(stroke
				(width 0.1)
				(type default)
			)
			(layer "F.Fab")
		)
		(fp_line
			(start -0.674878 -1.100074)
			(end 0.674878 -1.100074)
			(stroke
				(width 0.1)
				(type default)
			)
			(layer "F.Fab")
		)
		(fp_poly
			(pts
				(xy -1.4605 -0.7493) (xy -2.2225 -1.1303) (xy -2.2225 -0.3683)
			)
			(stroke
				(width 0)
				(type default)
			)
			(fill yes)
			(layer "F.Fab")
		)
		(pad "1" smd rect
			(at -0.899922 -0.750062 90)
			(size 0.6096 0.6096)
			(layers "F.Cu" "F.Mask" "F.Paste")
			(net "GND")
		)
		(pad "2" smd rect
			(at -0.899922 0 90)
			(size 0.4064 0.6096)
			(layers "F.Cu" "F.Mask" "F.Paste")
			(net "RST_PLD_CPU1_DRAM_EF_N")
		)
		(pad "3" smd rect
			(at -0.899922 0.750062 90)
			(size 0.6096 0.6096)
			(layers "F.Cu" "F.Mask" "F.Paste")
			(net "LED_RST_PLD_CPU1_DRAM_GH_N_D")
		)
		(pad "4" smd rect
			(at 0.899922 0.750062 90)
			(size 0.6096 0.6096)
			(layers "F.Cu" "F.Mask" "F.Paste")
			(net "GND")
		)
		(pad "5" smd rect
			(at 0.899922 0 90)
			(size 0.4064 0.6096)
			(layers "F.Cu" "F.Mask" "F.Paste")
			(net "RST_PLD_CPU1_DRAM_GH_N")
		)
		(pad "6" smd rect
			(at 0.899922 -0.750062 90)
			(size 0.6096 0.6096)
			(layers "F.Cu" "F.Mask" "F.Paste")
			(net "LED_RST_PLD_CPU1_DRAM_EF_N_D")
		)
	)
	(footprint ""
		(layer "F.Cu")
		(at 77.595476 -79.078836)
		(property "Reference" "D74"
			(at -40.11041 34.331402 90)
			(unlocked yes)
			(layer "F.SilkS")
			(effects
				(font
					(size 0.635 0.4064)
					(thickness 0.1524)
				)
				(justify left)
			)
		)
		(property "Value" ""
			(at 0 0 0)
			(layer "F.Fab")
			(effects
				(font
					(size 1.27 1.27)
				)
			)
		)
		(duplicate_pad_numbers_are_jumpers no)
		(fp_line
			(start -0.90678 0.4826)
			(end -0.90678 -0.4699)
			(stroke
				(width 0.1524)
				(type default)
			)
			(layer "F.SilkS")
		)
		(fp_line
			(start -0.89408 -0.4826)
			(end 0.90678 -0.4826)
			(stroke
				(width 0.1524)
				(type default)
			)
			(layer "F.SilkS")
		)
		(fp_line
			(start -0.79248 -0.4826)
			(end 1.03378 -0.4826)
			(stroke
				(width 0.1524)
				(type default)
			)
			(layer "F.SilkS")
		)
		(fp_line
			(start -0.64008 -0.4826)
			(end 1.16078 -0.4826)
			(stroke
				(width 0.1524)
				(type default)
			)
			(layer "F.SilkS")
		)
		(fp_line
			(start 0.90678 -0.4826)
			(end 0.90678 0.4826)
			(stroke
				(width 0.1524)
				(type default)
			)
			(layer "F.SilkS")
		)
		(fp_line
			(start 0.90678 0.4826)
			(end -0.90678 0.4826)
			(stroke
				(width 0.1524)
				(type default)
			)
			(layer "F.SilkS")
		)
		(fp_line
			(start 1.03378 -0.4826)
			(end 1.03378 0.4826)
			(stroke
				(width 0.1524)
				(type default)
			)
			(layer "F.SilkS")
		)
		(fp_line
			(start 1.03378 0.4826)
			(end -0.79248 0.4826)
			(stroke
				(width 0.1524)
				(type default)
			)
			(layer "F.SilkS")
		)
		(fp_line
			(start 1.16078 -0.4826)
			(end 1.16078 0.4826)
			(stroke
				(width 0.1524)
				(type default)
			)
			(layer "F.SilkS")
		)
		(fp_line
			(start 1.16078 0.4826)
			(end -0.64008 0.4826)
			(stroke
				(width 0.1524)
				(type default)
			)
			(layer "F.SilkS")
		)
		(fp_line
			(start -0.499872 -0.249936)
			(end 0.499872 -0.249936)
			(stroke
				(width 0.1)
				(type default)
			)
			(layer "F.Fab")
		)
		(fp_line
			(start -0.499872 0.249936)
			(end -0.499872 -0.249936)
			(stroke
				(width 0.1)
				(type default)
			)
			(layer "F.Fab")
		)
		(fp_line
			(start 0.499872 -0.249936)
			(end 0.499872 0.249936)
			(stroke
				(width 0.1)
				(type default)
			)
			(layer "F.Fab")
		)
		(fp_line
			(start 0.499872 0.249936)
			(end -0.499872 0.249936)
			(stroke
				(width 0.1)
				(type default)
			)
			(layer "F.Fab")
		)
		(pad "A" smd rect
			(at -0.47498 0)
			(size 0.6096 0.7112)
			(layers "F.Cu" "F.Mask" "F.Paste")
			(net "LED_PWRGD_PVPP_HBM_CPU0")
		)
		(pad "C" smd rect
			(at 0.47498 0)
			(size 0.6096 0.7112)
			(layers "F.Cu" "F.Mask" "F.Paste")
			(net "LED_PWRGD_PVPP_HBM_CPU0_D")
		)
	)
)
